# BASEBOARD_FAB2 (Tioga Pass) — schematic netlist excerpt (pin names and nets, part order shuffled) for the footprints in the layout excerpt that follows; sources: Cadence DE-HDL packaged netlist, KiCad conversion of Wiwynn_Tioga_Pass_MB.brd

J1B1  SCONN288_H44441004  SCONN  pkg PIP  page 83
  \12v\(1)  = P12V_NVDIMM_KLM
  VSS(93)  = GND
  DQ(4)  = M_K_DQ<5>
  VSS(92)  = GND
  DQ(0)  = M_K_DQ<1>
  VSS(91)  = GND
  DQS9P  = M_K_DQS_DP<9>
  DQS9N  = M_K_DQS_DN<9>
  VSS(90)  = GND
  DQ(6)  = M_K_DQ<7>
  VSS(89)  = GND
  DQ(2)  = M_K_DQ<3>
  VSS(88)  = GND
  DQ(12)  = M_K_DQ<13>
  VSS(87)  = GND
  DQ(8)  = M_K_DQ<9>
  VSS(86)  = GND
  DQS10P  = M_K_DQS_DP<10>
  DQS10N  = M_K_DQS_DN<10>
  VSS(85)  = GND
  DQ(14)  = M_K_DQ<15>
  VSS(84)  = GND
  DQ(10)  = M_K_DQ<11>
  VSS(83)  = GND
  DQ(20)  = M_K_DQ<21>
  VSS(82)  = GND
  DQ(16)  = M_K_DQ<17>
  VSS(81)  = GND
  DQS11P  = M_K_DQS_DP<11>
  DQS11N  = M_K_DQS_DN<11>
  VSS(80)  = GND
  DQ(22)  = M_K_DQ<23>
  VSS(79)  = GND
  DQ(18)  = M_K_DQ<19>
  VSS(78)  = GND
  DQ(28)  = M_K_DQ<29>
  VSS(77)  = GND
  DQ(24)  = M_K_DQ<25>
  VSS(76)  = GND
  DQS12P  = M_K_DQS_DP<12>
  DQS12N  = M_K_DQS_DN<12>
  VSS(75)  = GND
  DQ(30)  = M_K_DQ<31>
  VSS(74)  = GND
  DQ(26)  = M_K_DQ<27>
  VSS(73)  = GND
  CB(4)  = M_K_ECC<5>
  VSS(72)  = GND
  CB(0)  = M_K_ECC<1>
  VSS(71)  = GND
  DQS17P  = M_K_DQS_DP<17>
  DQS17N  = M_K_DQS_DN<17>
  VSS(70)  = GND
  CB(6)  = M_K_ECC<7>
  VSS(69)  = GND
  CB(2)  = M_K_ECC<3>
  VSS(68)  = GND
  RESET_N  = M_KLM_RST_N
  VDD(25)  = PVDDQ_KLM
  CKE(0)  = M_K_CKE<0>
  VDD(24)  = PVDDQ_KLM
  ACT_N  = M_K_ACT_N
  BG(0)  = M_K_BG<0>
  VDD(23)  = PVDDQ_KLM
  A12  = M_K_MA<12>
  A9  = M_K_MA<9>
  VDD(22)  = PVDDQ_KLM
  A8  = M_K_MA<8>
  A6  = M_K_MA<6>
  VDD(21)  = PVDDQ_KLM
  A3  = M_K_MA<3>
  A1  = M_K_MA<1>
  VDD(20)  = PVDDQ_KLM
  CK0P  = M_K_CLK_DP<0>
  CK0N  = M_K_CLK_DN<0>
  VDD(19)  = PVDDQ_KLM
  VTT(1)  = PVTT_KLM
  EVENT_N  = FM_DIMM_EVENT_COD_N
  A0  = M_K_MA<0>
  VDD(18)  = PVDDQ_KLM
  BA(0)  = M_K_BA<0>
  A16_RAS_N  = M_K_MA<16>
  VDD(17)  = PVDDQ_KLM
  S0_N  = M_K_CS_N<0>
  VDD(16)  = PVDDQ_KLM
  A15_CAS_N  = M_K_MA<15>
  ODT(0)  = M_K_ODT<0>
  VDD(15)  = PVDDQ_KLM
  S1_N  = M_K_CS_N<1>
  VDD(14)  = PVDDQ_KLM
  ODT(1)  = M_K_ODT<1>
  VDD(13)  = PVDDQ_KLM
  S2_N_C(0)  = M_K_CS_N<2>
  VSS(67)  = GND
  DQ(36)  = M_K_DQ<37>
  VSS(66)  = GND
  DQ(32)  = M_K_DQ<33>
  VSS(65)  = GND
  DQS13P  = M_K_DQS_DP<13>
  DQS13N  = M_K_DQS_DN<13>
  VSS(64)  = GND
  DQ(38)  = M_K_DQ<39>
  VSS(63)  = GND
  DQ(34)  = M_K_DQ<35>
  VSS(62)  = GND
  DQ(44)  = M_K_DQ<45>
  VSS(61)  = GND
  DQ(40)  = M_K_DQ<41>
  VSS(60)  = GND
  DQS14P  = M_K_DQS_DP<14>
  DQS14N  = M_K_DQS_DN<14>
  VSS(59)  = GND
  DQ(46)  = M_K_DQ<47>
  VSS(58)  = GND
  DQ(42)  = M_K_DQ<43>
  VSS(57)  = GND
  DQ(52)  = M_K_DQ<53>
  VSS(56)  = GND
  DQ(48)  = M_K_DQ<49>
  VSS(55)  = GND
  DQS15P  = M_K_DQS_DP<15>
  DQS15N  = M_K_DQS_DN<15>
  VSS(54)  = GND
  DQ(54)  = M_K_DQ<55>
  VSS(53)  = GND
  DQ(50)  = M_K_DQ<51>
  VSS(52)  = GND
  DQ(60)  = M_K_DQ<61>
  VSS(51)  = GND
  DQ(56)  = M_K_DQ<57>
  VSS(50)  = GND
  DQS16P  = M_K_DQS_DP<16>
  DQS16N  = M_K_DQS_DN<16>
  VSS(49)  = GND
  DQ(62)  = M_K_DQ<63>
  VSS(48)  = GND
  DQ(58)  = M_K_DQ<59>
  VSS(47)  = GND
  SA(0)  = GND
  SA(1)  = GND
  SCL  = SMB_DDR_KLM_VPP_SCL
  VPP(4)  = PVPP_KLM
  VPP(3)  = PVPP_KLM
  RFU(2)  = TP_CH_K_DIMM_K0_RFU_2
  \12v\(0)  = P12V_NVDIMM_KLM
  VREFCA  = M_K_VREF
  VSS(46)  = GND
  DQ(5)  = M_K_DQ<4>
  VSS(45)  = GND
  DQ(1)  = M_K_DQ<0>
  VSS(44)  = GND
  DQS0N  = M_K_DQS_DN<0>
  DQS0P  = M_K_DQS_DP<0>
  VSS(43)  = GND
  DQ(7)  = M_K_DQ<6>
  VSS(42)  = GND
  DQ(3)  = M_K_DQ<2>
  VSS(41)  = GND
  DQ(13)  = M_K_DQ<12>
  VSS(40)  = GND
  DQ(9)  = M_K_DQ<8>
  VSS(39)  = GND
  DQS1N  = M_K_DQS_DN<1>
  DQS1P  = M_K_DQS_DP<1>
  VSS(38)  = GND
  DQ(15)  = M_K_DQ<14>
  VSS(37)  = GND
  DQ(11)  = M_K_DQ<10>
  VSS(36)  = GND
  DQ(21)  = M_K_DQ<20>
  VSS(35)  = GND
  DQ(17)  = M_K_DQ<16>
  VSS(34)  = GND
  DQS2N  = M_K_DQS_DN<2>
  DQS2P  = M_K_DQS_DP<2>
  VSS(33)  = GND
  DQ(23)  = M_K_DQ<22>
  VSS(32)  = GND
  DQ(19)  = M_K_DQ<18>
  VSS(31)  = GND
  DQ(29)  = M_K_DQ<28>
  VSS(30)  = GND
  DQ(25)  = M_K_DQ<24>
  VSS(29)  = GND
  DQS3N  = M_K_DQS_DN<3>
  DQS3P  = M_K_DQS_DP<3>
  VSS(28)  = GND
  DQ(31)  = M_K_DQ<30>
  VSS(27)  = GND
  DQ(27)  = M_K_DQ<26>
  VSS(26)  = GND
  CB(5)  = M_K_ECC<4>
  VSS(25)  = GND
  CB(1)  = M_K_ECC<0>
  VSS(24)  = GND
  DQS8N  = M_K_DQS_DN<8>
  DQS8P  = M_K_DQS_DP<8>
  VSS(23)  = GND
  CB(7)  = M_K_ECC<6>
  VSS(22)  = GND
  CB(3)  = M_K_ECC<2>
  VSS(21)  = GND
  CKE(1)  = M_K_CKE<1>
  VDD(12)  = PVDDQ_KLM
  RFU(0)  = TP_CH_K_DIMM_K0_RFU_0
  VDD(11)  = PVDDQ_KLM
  BG(1)  = M_K_BG<1>
  ALERT_N  = M_K_ALERT_N
  VDD(10)  = PVDDQ_KLM
  A11  = M_K_MA<11>
  A7  = M_K_MA<7>
  VDD(9)  = PVDDQ_KLM
  A5  = M_K_MA<5>
  A4  = M_K_MA<4>
  VDD(8)  = PVDDQ_KLM
  A2  = M_K_MA<2>
  VDD(7)  = PVDDQ_KLM
  CK1P  = M_K_CLK_DP<1>
  CK1N  = M_K_CLK_DN<1>
  VDD(6)  = PVDDQ_KLM
  VTT(0)  = PVTT_KLM
  PAR  = M_K_PAR
  VDD(5)  = PVDDQ_KLM
  BA(1)  = M_K_BA<1>
  A10  = M_K_MA<10>
  VDD(4)  = PVDDQ_KLM
  RFU(1)  = TP_CH_K_DIMM_K0_RFU_1
  A14_WE_N  = M_K_MA<14>
  VDD(3)  = PVDDQ_KLM
  SAVE_N_NC  = FM_ADR_COMPLETE_KLM_N
  VDD(2)  = PVDDQ_KLM
  A13  = M_K_MA<13>
  VDD(1)  = PVDDQ_KLM
  A17  = M_K_MA<17>
  C(2)  = M_K_C<2>
  VDD(0)  = PVDDQ_KLM
  S3_N_C(1)  = M_K_CS_N<3>
  SA(2)  = GND
  VSS(20)  = GND
  DQ(37)  = M_K_DQ<36>
  VSS(19)  = GND
  DQ(33)  = M_K_DQ<32>
  VSS(18)  = GND
  DQS4N  = M_K_DQS_DN<4>
  DQS4P  = M_K_DQS_DP<4>
  VSS(17)  = GND
  DQ(39)  = M_K_DQ<38>
  VSS(16)  = GND
  DQ(35)  = M_K_DQ<34>
  VSS(15)  = GND
  DQ(45)  = M_K_DQ<44>
  VSS(14)  = GND
  DQ(41)  = M_K_DQ<40>
  VSS(13)  = GND
  DQS5N  = M_K_DQS_DN<5>
  DQS5P  = M_K_DQS_DP<5>
  VSS(12)  = GND
  DQ(47)  = M_K_DQ<46>
  VSS(11)  = GND
  DQ(43)  = M_K_DQ<42>
  VSS(10)  = GND
  DQ(53)  = M_K_DQ<52>
  VSS(9)  = GND
  DQ(49)  = M_K_DQ<48>
  VSS(8)  = GND
  DQS6N  = M_K_DQS_DN<6>
  DQS6P  = M_K_DQS_DP<6>
  VSS(7)  = GND
  DQ(55)  = M_K_DQ<54>
  VSS(6)  = GND
  DQ(51)  = M_K_DQ<50>
  VSS(5)  = GND
  DQ(61)  = M_K_DQ<60>
  VSS(4)  = GND
  DQ(57)  = M_K_DQ<56>
  VSS(3)  = GND
  DQS7N  = M_K_DQS_DN<7>
  DQS7P  = M_K_DQS_DP<7>
  VSS(2)  = GND
  DQ(63)  = M_K_DQ<62>
  VSS(1)  = GND
  DQ(59)  = M_K_DQ<58>
  VSS(0)  = GND
  VDDSPD  = PVPP_KLM
  SDA  = SMB_DDR_KLM_VPP_SDA
  VPP(1)  = PVPP_KLM
  VPP(0)  = PVPP_KLM
  VPP(2)  = PVPP_KLM

(kicad_pcb
	(version 20260206)
	(generator "pcbnew")
	(generator_version "10.0")
	(general
		(thickness 1.6)
		(legacy_teardrops no)
	)
	(paper "A4")
	(title_block
		(title "Wiwynn_Tioga_Pass_MB.brd")
		(comment 1 "Tioga Pass / footprint 320 of 4770 (J1B1), pads 252-291 of 291")
	)
	(layers
		(0 "F.Cu" signal "TOP")
		(4 "In1.Cu" signal "L2GND")
		(6 "In2.Cu" signal "L3")
		(8 "In3.Cu" signal "L4GND")
		(10 "In4.Cu" signal "L5")
		(12 "In5.Cu" signal "L6GND")
		(14 "In6.Cu" signal "L7VCC")
		(16 "In7.Cu" signal "L8VCC")
		(18 "In8.Cu" signal "L9GND")
		(20 "In9.Cu" signal "L10")
		(22 "In10.Cu" signal "L11GND")
		(24 "In11.Cu" signal "L12")
		(26 "In12.Cu" signal "L13GND")
		(2 "B.Cu" signal "BOTTOM")
		(9 "F.Adhes" user "F.Adhesive")
		(11 "B.Adhes" user "B.Adhesive")
		(13 "F.Paste" user "Package Geometry/Pastemask Top")
		(15 "B.Paste" user "Package Geometry/Pastemask Bottom")
		(5 "F.SilkS" user "Ref Des/Silkscreen Top")
		(7 "B.SilkS" user "Ref Des/Silkscreen Bottom")
		(1 "F.Mask" user "Board Geometry/Soldermask Top")
		(3 "B.Mask" user "Board Geometry/Soldermask Bottom")
		(17 "Dwgs.User" user "User.Drawings")
		(19 "Cmts.User" user "User.Comments")
		(21 "Eco1.User" user "User.Eco1")
		(23 "Eco2.User" user "User.Eco2")
		(25 "Edge.Cuts" user "Board Geometry/Outline")
		(27 "Margin" user)
		(31 "F.CrtYd" user "Package Geometry/Place Bound Top")
		(29 "B.CrtYd" user "Package Geometry/Place Bound Bottom")
		(35 "F.Fab" user "Ref Des/Assembly Top")
		(33 "B.Fab" user "Ref Des/Assembly Bottom")
	)
	(footprint ""
		(layer "F.Cu")
		(at 29.699458 -133.0706 90)
		(property "Reference" "J1B1"
			(at -4.960112 38.372542 0)
			(unlocked yes)
			(layer "F.SilkS")
			(effects
				(font
					(size 0.7874 0.5842)
					(thickness 0.1524)
				)
				(justify left)
			)
		)
		(property "Value" ""
			(at 0 0 90)
			(layer "F.Fab")
			(effects
				(font
					(size 1.27 1.27)
				)
			)
		)
		(duplicate_pad_numbers_are_jumpers no)
		(pad "249" smd rect
			(at 4.59994 93.49994 90)
			(size 1.8034 0.508)
			(layers "F.Cu" "F.Mask" "F.Paste")
			(net "M_K_DQ<34>")
		)
		(pad "250" smd rect
			(at 4.59994 94.350078 90)
			(size 1.8034 0.508)
			(layers "F.Cu" "F.Mask" "F.Paste")
			(net "GND")
		)
		(pad "251" smd rect
			(at 4.59994 95.199962 90)
			(size 1.8034 0.508)
			(layers "F.Cu" "F.Mask" "F.Paste")
			(net "M_K_DQ<44>")
		)
		(pad "252" smd rect
			(at 4.59994 96.0501 90)
			(size 1.8034 0.508)
			(layers "F.Cu" "F.Mask" "F.Paste")
			(net "GND")
		)
		(pad "253" smd rect
			(at 4.59994 96.899984 90)
			(size 1.8034 0.508)
			(layers "F.Cu" "F.Mask" "F.Paste")
			(net "M_K_DQ<40>")
		)
		(pad "254" smd rect
			(at 4.59994 97.750122 90)
			(size 1.8034 0.508)
			(layers "F.Cu" "F.Mask" "F.Paste")
			(net "GND")
		)
		(pad "255" smd rect
			(at 4.59994 98.600006 90)
			(size 1.8034 0.508)
			(layers "F.Cu" "F.Mask" "F.Paste")
			(net "M_K_DQS_DN<5>")
		)
		(pad "256" smd rect
			(at 4.59994 99.44989 90)
			(size 1.8034 0.508)
			(layers "F.Cu" "F.Mask" "F.Paste")
			(net "M_K_DQS_DP<5>")
		)
		(pad "257" smd rect
			(at 4.59994 100.300028 90)
			(size 1.8034 0.508)
			(layers "F.Cu" "F.Mask" "F.Paste")
			(net "GND")
		)
		(pad "258" smd rect
			(at 4.59994 101.149912 90)
			(size 1.8034 0.508)
			(layers "F.Cu" "F.Mask" "F.Paste")
			(net "M_K_DQ<46>")
		)
		(pad "259" smd rect
			(at 4.59994 102.00005 90)
			(size 1.8034 0.508)
			(layers "F.Cu" "F.Mask" "F.Paste")
			(net "GND")
		)
		(pad "260" smd rect
			(at 4.59994 102.849934 90)
			(size 1.8034 0.508)
			(layers "F.Cu" "F.Mask" "F.Paste")
			(net "M_K_DQ<42>")
		)
		(pad "261" smd rect
			(at 4.59994 103.700072 90)
			(size 1.8034 0.508)
			(layers "F.Cu" "F.Mask" "F.Paste")
			(net "GND")
		)
		(pad "262" smd rect
			(at 4.59994 104.549956 90)
			(size 1.8034 0.508)
			(layers "F.Cu" "F.Mask" "F.Paste")
			(net "M_K_DQ<52>")
		)
		(pad "263" smd rect
			(at 4.59994 105.400094 90)
			(size 1.8034 0.508)
			(layers "F.Cu" "F.Mask" "F.Paste")
			(net "GND")
		)
		(pad "264" smd rect
			(at 4.59994 106.249978 90)
			(size 1.8034 0.508)
			(layers "F.Cu" "F.Mask" "F.Paste")
			(net "M_K_DQ<48>")
		)
		(pad "265" smd rect
			(at 4.59994 107.100116 90)
			(size 1.8034 0.508)
			(layers "F.Cu" "F.Mask" "F.Paste")
			(net "GND")
		)
		(pad "266" smd rect
			(at 4.59994 107.95 90)
			(size 1.8034 0.508)
			(layers "F.Cu" "F.Mask" "F.Paste")
			(net "M_K_DQS_DN<6>")
		)
		(pad "267" smd rect
			(at 4.59994 108.799884 90)
			(size 1.8034 0.508)
			(layers "F.Cu" "F.Mask" "F.Paste")
			(net "M_K_DQS_DP<6>")
		)
		(pad "268" smd rect
			(at 4.59994 109.650022 90)
			(size 1.8034 0.508)
			(layers "F.Cu" "F.Mask" "F.Paste")
			(net "GND")
		)
		(pad "269" smd rect
			(at 4.59994 110.499906 90)
			(size 1.8034 0.508)
			(layers "F.Cu" "F.Mask" "F.Paste")
			(net "M_K_DQ<54>")
		)
		(pad "270" smd rect
			(at 4.59994 111.350044 90)
			(size 1.8034 0.508)
			(layers "F.Cu" "F.Mask" "F.Paste")
			(net "GND")
		)
		(pad "271" smd rect
			(at 4.59994 112.199928 90)
			(size 1.8034 0.508)
			(layers "F.Cu" "F.Mask" "F.Paste")
			(net "M_K_DQ<50>")
		)
		(pad "272" smd rect
			(at 4.59994 113.050066 90)
			(size 1.8034 0.508)
			(layers "F.Cu" "F.Mask" "F.Paste")
			(net "GND")
		)
		(pad "273" smd rect
			(at 4.59994 113.89995 90)
			(size 1.8034 0.508)
			(layers "F.Cu" "F.Mask" "F.Paste")
			(net "M_K_DQ<60>")
		)
		(pad "274" smd rect
			(at 4.59994 114.750088 90)
			(size 1.8034 0.508)
			(layers "F.Cu" "F.Mask" "F.Paste")
			(net "GND")
		)
		(pad "275" smd rect
			(at 4.59994 115.599972 90)
			(size 1.8034 0.508)
			(layers "F.Cu" "F.Mask" "F.Paste")
			(net "M_K_DQ<56>")
		)
		(pad "276" smd rect
			(at 4.59994 116.45011 90)
			(size 1.8034 0.508)
			(layers "F.Cu" "F.Mask" "F.Paste")
			(net "GND")
		)
		(pad "277" smd rect
			(at 4.59994 117.299994 90)
			(size 1.8034 0.508)
			(layers "F.Cu" "F.Mask" "F.Paste")
			(net "M_K_DQS_DN<7>")
		)
		(pad "278" smd rect
			(at 4.59994 118.149878 90)
			(size 1.8034 0.508)
			(layers "F.Cu" "F.Mask" "F.Paste")
			(net "M_K_DQS_DP<7>")
		)
		(pad "279" smd rect
			(at 4.59994 119.000016 90)
			(size 1.8034 0.508)
			(layers "F.Cu" "F.Mask" "F.Paste")
			(net "GND")
		)
		(pad "280" smd rect
			(at 4.59994 119.8499 90)
			(size 1.8034 0.508)
			(layers "F.Cu" "F.Mask" "F.Paste")
			(net "M_K_DQ<62>")
		)
		(pad "281" smd rect
			(at 4.59994 120.700038 90)
			(size 1.8034 0.508)
			(layers "F.Cu" "F.Mask" "F.Paste")
			(net "GND")
		)
		(pad "282" smd rect
			(at 4.59994 121.549922 90)
			(size 1.8034 0.508)
			(layers "F.Cu" "F.Mask" "F.Paste")
			(net "M_K_DQ<58>")
		)
		(pad "283" smd rect
			(at 4.59994 122.40006 90)
			(size 1.8034 0.508)
			(layers "F.Cu" "F.Mask" "F.Paste")
			(net "GND")
		)
		(pad "284" smd rect
			(at 4.59994 123.249944 90)
			(size 1.8034 0.508)
			(layers "F.Cu" "F.Mask" "F.Paste")
			(net "PVPP_KLM")
		)
		(pad "285" smd rect
			(at 4.59994 124.100082 90)
			(size 1.8034 0.508)
			(layers "F.Cu" "F.Mask" "F.Paste")
			(net "SMB_DDR_KLM_VPP_SDA")
		)
		(pad "286" smd rect
			(at 4.59994 124.949966 90)
			(size 1.8034 0.508)
			(layers "F.Cu" "F.Mask" "F.Paste")
			(net "PVPP_KLM")
		)
		(pad "287" smd rect
			(at 4.59994 125.800104 90)
			(size 1.8034 0.508)
			(layers "F.Cu" "F.Mask" "F.Paste")
			(net "PVPP_KLM")
		)
		(pad "288" smd rect
			(at 4.59994 126.649988 90)
			(size 1.8034 0.508)
			(layers "F.Cu" "F.Mask" "F.Paste")
			(net "PVPP_KLM")
		)
	)
)
